(kicad_pcb
	(version 20260206)
	(generator "pcbnew")
	(generator_version "10.0")
	(general
		(thickness 1.6)
		(legacy_teardrops no)
	)
	(paper "A4")
	(title_block
		(title "04192023_DAF0TMB3IC0_F0TG_MB_C_brd_V02_OCP.brd")
		(comment 1 "Grand Teton / footprints 6824-6829 of 8354")
	)
	(layers
		(0 "F.Cu" signal "TOP")
		(4 "In1.Cu" signal "GND")
		(6 "In2.Cu" signal "IN1")
		(8 "In3.Cu" signal "GND1")
		(10 "In4.Cu" signal "IN2")
		(12 "In5.Cu" signal "GND2")
		(14 "In6.Cu" signal "IN3")
		(16 "In7.Cu" signal "GND3")
		(18 "In8.Cu" signal "VCC")
		(20 "In9.Cu" signal "VCC1")
		(22 "In10.Cu" signal "GND4")
		(24 "In11.Cu" signal "IN4")
		(26 "In12.Cu" signal "GND5")
		(28 "In13.Cu" signal "IN5")
		(30 "In14.Cu" signal "GND6")
		(32 "In15.Cu" signal "IN6")
		(34 "In16.Cu" signal "GND7")
		(2 "B.Cu" signal "BOTTOM")
		(9 "F.Adhes" user "F.Adhesive")
		(11 "B.Adhes" user "B.Adhesive")
		(13 "F.Paste" user "Package Geometry/Pastemask Top")
		(15 "B.Paste" user "Package Geometry/Pastemask Bottom")
		(5 "F.SilkS" user "Ref Des/Silkscreen Top")
		(7 "B.SilkS" user "Ref Des/Silkscreen Bottom")
		(1 "F.Mask" user "Board Geometry/Soldermask Top")
		(3 "B.Mask" user "Board Geometry/Soldermask Bottom")
		(17 "Dwgs.User" user "User.Drawings")
		(19 "Cmts.User" user "User.Comments")
		(21 "Eco1.User" user "User.Eco1")
		(23 "Eco2.User" user "User.Eco2")
		(25 "Edge.Cuts" user "Board Geometry/Outline")
		(27 "Margin" user)
		(31 "F.CrtYd" user "Package Geometry/Place Bound Top")
		(29 "B.CrtYd" user "Package Geometry/Place Bound Bottom")
		(35 "F.Fab" user "Ref Des/Assembly Top")
		(33 "B.Fab" user "Ref Des/Assembly Bottom")
	)
	(footprint ""
		(layer "B.Cu")
		(at 310.411876 -66.708782 90)
		(property "Reference" "R3074"
			(at 0 0 90)
			(layer "B.SilkS")
			(hide yes)
			(effects
				(font
					(size 1.27 1.27)
				)
				(justify mirror)
			)
		)
		(property "Value" ""
			(at 0 0 90)
			(layer "B.Fab")
			(effects
				(font
					(size 1.27 1.27)
				)
				(justify mirror)
			)
		)
		(duplicate_pad_numbers_are_jumpers no)
		(fp_line
			(start 0.7874 -0.4064)
			(end -0.7874 -0.4064)
			(stroke
				(width 0.1524)
				(type default)
			)
			(layer "B.SilkS")
		)
		(fp_line
			(start -0.7874 -0.4064)
			(end -0.7874 0.4064)
			(stroke
				(width 0.1524)
				(type default)
			)
			(layer "B.SilkS")
		)
		(fp_line
			(start 0.7874 0.4064)
			(end 0.7874 -0.4064)
			(stroke
				(width 0.1524)
				(type default)
			)
			(layer "B.SilkS")
		)
		(fp_line
			(start -0.7874 0.4064)
			(end 0.7874 0.4064)
			(stroke
				(width 0.1524)
				(type default)
			)
			(layer "B.SilkS")
		)
		(fp_line
			(start 0.67945 -0.305054)
			(end 0.12065 -0.305054)
			(stroke
				(width 0.1)
				(type default)
			)
			(layer "B.Fab")
		)
		(fp_line
			(start 0.12065 -0.305054)
			(end 0.12065 -0.2794)
			(stroke
				(width 0.1)
				(type default)
			)
			(layer "B.Fab")
		)
		(fp_line
			(start -0.12065 -0.3048)
			(end -0.67945 -0.3048)
			(stroke
				(width 0.1)
				(type default)
			)
			(layer "B.Fab")
		)
		(fp_line
			(start -0.67945 -0.3048)
			(end -0.67945 0.3048)
			(stroke
				(width 0.1)
				(type default)
			)
			(layer "B.Fab")
		)
		(fp_line
			(start 0.12065 -0.2794)
			(end -0.12065 -0.2794)
			(stroke
				(width 0.1)
				(type default)
			)
			(layer "B.Fab")
		)
		(fp_line
			(start -0.12065 -0.2794)
			(end -0.12065 -0.3048)
			(stroke
				(width 0.1)
				(type default)
			)
			(layer "B.Fab")
		)
		(fp_line
			(start 0.12065 0.2794)
			(end 0.12065 0.3048)
			(stroke
				(width 0.1)
				(type default)
			)
			(layer "B.Fab")
		)
		(fp_line
			(start -0.120396 0.2794)
			(end 0.12065 0.2794)
			(stroke
				(width 0.1)
				(type default)
			)
			(layer "B.Fab")
		)
		(fp_line
			(start 0.67945 0.3048)
			(end 0.67945 -0.305054)
			(stroke
				(width 0.1)
				(type default)
			)
			(layer "B.Fab")
		)
		(fp_line
			(start 0.12065 0.3048)
			(end 0.67945 0.3048)
			(stroke
				(width 0.1)
				(type default)
			)
			(layer "B.Fab")
		)
		(fp_line
			(start -0.120396 0.3048)
			(end -0.120396 0.2794)
			(stroke
				(width 0.1)
				(type default)
			)
			(layer "B.Fab")
		)
		(fp_line
			(start -0.67945 0.3048)
			(end -0.120396 0.3048)
			(stroke
				(width 0.1)
				(type default)
			)
			(layer "B.Fab")
		)
		(pad "1" smd circle
			(at 0.40005 0 270)
			(size 0 0)
			(layers "B.Cu" "B.Mask" "B.Paste")
			(net "LED_RST_RSMRST_PLD_R_N")
		)
		(pad "2" smd circle
			(at -0.40005 0 270)
			(size 0 0)
			(layers "B.Cu" "B.Mask" "B.Paste")
			(net "P3V3_AUX")
		)
	)
	(footprint ""
		(layer "B.Cu")
		(at 114.327178 -261.748016 90)
		(property "Reference" "C2506"
			(at 0 0 90)
			(layer "B.SilkS")
			(hide yes)
			(effects
				(font
					(size 1.27 1.27)
				)
				(justify mirror)
			)
		)
		(property "Value" ""
			(at 0 0 90)
			(layer "B.Fab")
			(effects
				(font
					(size 1.27 1.27)
				)
				(justify mirror)
			)
		)
		(duplicate_pad_numbers_are_jumpers no)
		(fp_line
			(start 0.7874 -0.4064)
			(end -0.7874 -0.4064)
			(stroke
				(width 0.1524)
				(type default)
			)
			(layer "B.SilkS")
		)
		(fp_line
			(start -0.7874 -0.4064)
			(end -0.7874 0.4064)
			(stroke
				(width 0.1524)
				(type default)
			)
			(layer "B.SilkS")
		)
		(fp_line
			(start 0.7874 0.4064)
			(end 0.7874 -0.4064)
			(stroke
				(width 0.1524)
				(type default)
			)
			(layer "B.SilkS")
		)
		(fp_line
			(start -0.7874 0.4064)
			(end 0.7874 0.4064)
			(stroke
				(width 0.1524)
				(type default)
			)
			(layer "B.SilkS")
		)
		(fp_line
			(start 0.67945 -0.305054)
			(end 0.12065 -0.305054)
			(stroke
				(width 0.1)
				(type default)
			)
			(layer "B.Fab")
		)
		(fp_line
			(start 0.12065 -0.305054)
			(end 0.12065 -0.2794)
			(stroke
				(width 0.1)
				(type default)
			)
			(layer "B.Fab")
		)
		(fp_line
			(start -0.12065 -0.3048)
			(end -0.67945 -0.3048)
			(stroke
				(width 0.1)
				(type default)
			)
			(layer "B.Fab")
		)
		(fp_line
			(start -0.67945 -0.3048)
			(end -0.67945 0.3048)
			(stroke
				(width 0.1)
				(type default)
			)
			(layer "B.Fab")
		)
		(fp_line
			(start 0.12065 -0.2794)
			(end -0.12065 -0.2794)
			(stroke
				(width 0.1)
				(type default)
			)
			(layer "B.Fab")
		)
		(fp_line
			(start -0.12065 -0.2794)
			(end -0.12065 -0.3048)
			(stroke
				(width 0.1)
				(type default)
			)
			(layer "B.Fab")
		)
		(fp_line
			(start 0.12065 0.2794)
			(end 0.12065 0.3048)
			(stroke
				(width 0.1)
				(type default)
			)
			(layer "B.Fab")
		)
		(fp_line
			(start -0.120396 0.2794)
			(end 0.12065 0.2794)
			(stroke
				(width 0.1)
				(type default)
			)
			(layer "B.Fab")
		)
		(fp_line
			(start 0.67945 0.3048)
			(end 0.67945 -0.305054)
			(stroke
				(width 0.1)
				(type default)
			)
			(layer "B.Fab")
		)
		(fp_line
			(start 0.12065 0.3048)
			(end 0.67945 0.3048)
			(stroke
				(width 0.1)
				(type default)
			)
			(layer "B.Fab")
		)
		(fp_line
			(start -0.120396 0.3048)
			(end -0.120396 0.2794)
			(stroke
				(width 0.1)
				(type default)
			)
			(layer "B.Fab")
		)
		(fp_line
			(start -0.67945 0.3048)
			(end -0.120396 0.3048)
			(stroke
				(width 0.1)
				(type default)
			)
			(layer "B.Fab")
		)
		(pad "1" smd circle
			(at 0.40005 0 270)
			(size 0 0)
			(layers "B.Cu" "B.Mask" "B.Paste")
			(net "PVDD11_S3_P1")
		)
		(pad "2" smd circle
			(at -0.40005 0 270)
			(size 0 0)
			(layers "B.Cu" "B.Mask" "B.Paste")
			(net "GND")
		)
	)
	(footprint ""
		(layer "B.Cu")
		(at 24.765 -362.204 180)
		(property "Reference" "R8242"
			(at 0 0 0)
			(layer "B.SilkS")
			(hide yes)
			(effects
				(font
					(size 1.27 1.27)
				)
				(justify mirror)
			)
		)
		(property "Value" ""
			(at 0 0 0)
			(layer "B.Fab")
			(effects
				(font
					(size 1.27 1.27)
				)
				(justify mirror)
			)
		)
		(duplicate_pad_numbers_are_jumpers no)
		(fp_line
			(start 0.7874 0.4064)
			(end 0.7874 -0.4064)
			(stroke
				(width 0.1524)
				(type default)
			)
			(layer "B.SilkS")
		)
		(fp_line
			(start 0.7874 -0.4064)
			(end -0.7874 -0.4064)
			(stroke
				(width 0.1524)
				(type default)
			)
			(layer "B.SilkS")
		)
		(fp_line
			(start -0.7874 0.4064)
			(end 0.7874 0.4064)
			(stroke
				(width 0.1524)
				(type default)
			)
			(layer "B.SilkS")
		)
		(fp_line
			(start -0.7874 -0.4064)
			(end -0.7874 0.4064)
			(stroke
				(width 0.1524)
				(type default)
			)
			(layer "B.SilkS")
		)
		(fp_line
			(start 0.67945 0.3048)
			(end 0.67945 -0.305054)
			(stroke
				(width 0.1)
				(type default)
			)
			(layer "B.Fab")
		)
		(fp_line
			(start 0.67945 -0.305054)
			(end 0.12065 -0.305054)
			(stroke
				(width 0.1)
				(type default)
			)
			(layer "B.Fab")
		)
		(fp_line
			(start 0.12065 0.3048)
			(end 0.67945 0.3048)
			(stroke
				(width 0.1)
				(type default)
			)
			(layer "B.Fab")
		)
		(fp_line
			(start 0.12065 0.2794)
			(end 0.12065 0.3048)
			(stroke
				(width 0.1)
				(type default)
			)
			(layer "B.Fab")
		)
		(fp_line
			(start 0.12065 -0.2794)
			(end -0.12065 -0.2794)
			(stroke
				(width 0.1)
				(type default)
			)
			(layer "B.Fab")
		)
		(fp_line
			(start 0.12065 -0.305054)
			(end 0.12065 -0.2794)
			(stroke
				(width 0.1)
				(type default)
			)
			(layer "B.Fab")
		)
		(fp_line
			(start -0.120396 0.3048)
			(end -0.120396 0.2794)
			(stroke
				(width 0.1)
				(type default)
			)
			(layer "B.Fab")
		)
		(fp_line
			(start -0.120396 0.2794)
			(end 0.12065 0.2794)
			(stroke
				(width 0.1)
				(type default)
			)
			(layer "B.Fab")
		)
		(fp_line
			(start -0.12065 -0.2794)
			(end -0.12065 -0.3048)
			(stroke
				(width 0.1)
				(type default)
			)
			(layer "B.Fab")
		)
		(fp_line
			(start -0.12065 -0.3048)
			(end -0.67945 -0.3048)
			(stroke
				(width 0.1)
				(type default)
			)
			(layer "B.Fab")
		)
		(fp_line
			(start -0.67945 0.3048)
			(end -0.120396 0.3048)
			(stroke
				(width 0.1)
				(type default)
			)
			(layer "B.Fab")
		)
		(fp_line
			(start -0.67945 -0.3048)
			(end -0.67945 0.3048)
			(stroke
				(width 0.1)
				(type default)
			)
			(layer "B.Fab")
		)
		(pad "1" smd circle
			(at 0.40005 0)
			(size 0 0)
			(layers "B.Cu" "B.Mask" "B.Paste")
			(net "P3V3_AUX")
		)
		(pad "2" smd circle
			(at -0.40005 0)
			(size 0 0)
			(layers "B.Cu" "B.Mask" "B.Paste")
			(net "PWRGD_PVDDIO_P1_R")
		)
	)
	(footprint ""
		(layer "B.Cu")
		(at 172.456094 -415.808668 180)
		(property "Reference" "R2909"
			(at 0 0 0)
			(layer "B.SilkS")
			(hide yes)
			(effects
				(font
					(size 1.27 1.27)
				)
				(justify mirror)
			)
		)
		(property "Value" ""
			(at 0 0 0)
			(layer "B.Fab")
			(effects
				(font
					(size 1.27 1.27)
				)
				(justify mirror)
			)
		)
		(duplicate_pad_numbers_are_jumpers no)
		(fp_line
			(start 0.7874 0.4064)
			(end 0.7874 -0.4064)
			(stroke
				(width 0.1524)
				(type default)
			)
			(layer "B.SilkS")
		)
		(fp_line
			(start 0.7874 -0.4064)
			(end -0.7874 -0.4064)
			(stroke
				(width 0.1524)
				(type default)
			)
			(layer "B.SilkS")
		)
		(fp_line
			(start -0.7874 0.4064)
			(end 0.7874 0.4064)
			(stroke
				(width 0.1524)
				(type default)
			)
			(layer "B.SilkS")
		)
		(fp_line
			(start -0.7874 -0.4064)
			(end -0.7874 0.4064)
			(stroke
				(width 0.1524)
				(type default)
			)
			(layer "B.SilkS")
		)
		(fp_line
			(start 0.67945 0.3048)
			(end 0.67945 -0.305054)
			(stroke
				(width 0.1)
				(type default)
			)
			(layer "B.Fab")
		)
		(fp_line
			(start 0.67945 -0.305054)
			(end 0.12065 -0.305054)
			(stroke
				(width 0.1)
				(type default)
			)
			(layer "B.Fab")
		)
		(fp_line
			(start 0.12065 0.3048)
			(end 0.67945 0.3048)
			(stroke
				(width 0.1)
				(type default)
			)
			(layer "B.Fab")
		)
		(fp_line
			(start 0.12065 0.2794)
			(end 0.12065 0.3048)
			(stroke
				(width 0.1)
				(type default)
			)
			(layer "B.Fab")
		)
		(fp_line
			(start 0.12065 -0.2794)
			(end -0.12065 -0.2794)
			(stroke
				(width 0.1)
				(type default)
			)
			(layer "B.Fab")
		)
		(fp_line
			(start 0.12065 -0.305054)
			(end 0.12065 -0.2794)
			(stroke
				(width 0.1)
				(type default)
			)
			(layer "B.Fab")
		)
		(fp_line
			(start -0.120396 0.3048)
			(end -0.120396 0.2794)
			(stroke
				(width 0.1)
				(type default)
			)
			(layer "B.Fab")
		)
		(fp_line
			(start -0.120396 0.2794)
			(end 0.12065 0.2794)
			(stroke
				(width 0.1)
				(type default)
			)
			(layer "B.Fab")
		)
		(fp_line
			(start -0.12065 -0.2794)
			(end -0.12065 -0.3048)
			(stroke
				(width 0.1)
				(type default)
			)
			(layer "B.Fab")
		)
		(fp_line
			(start -0.12065 -0.3048)
			(end -0.67945 -0.3048)
			(stroke
				(width 0.1)
				(type default)
			)
			(layer "B.Fab")
		)
		(fp_line
			(start -0.67945 0.3048)
			(end -0.120396 0.3048)
			(stroke
				(width 0.1)
				(type default)
			)
			(layer "B.Fab")
		)
		(fp_line
			(start -0.67945 -0.3048)
			(end -0.67945 0.3048)
			(stroke
				(width 0.1)
				(type default)
			)
			(layer "B.Fab")
		)
		(pad "1" smd circle
			(at 0.40005 0)
			(size 0 0)
			(layers "B.Cu" "B.Mask" "B.Paste")
			(net "P3V3_AUX")
		)
		(pad "2" smd circle
			(at -0.40005 0)
			(size 0 0)
			(layers "B.Cu" "B.Mask" "B.Paste")
			(net "RST_SWB_BIC_R_N")
		)
	)
	(footprint ""
		(layer "B.Cu")
		(at 14.892782 -415.644584 -90)
		(property "Reference" "PR6540"
			(at 0 0 90)
			(layer "B.SilkS")
			(hide yes)
			(effects
				(font
					(size 1.27 1.27)
				)
				(justify mirror)
			)
		)
		(property "Value" ""
			(at 0 0 90)
			(layer "B.Fab")
			(effects
				(font
					(size 1.27 1.27)
				)
				(justify mirror)
			)
		)
		(duplicate_pad_numbers_are_jumpers no)
		(fp_line
			(start -0.7874 0.4064)
			(end 0.7874 0.4064)
			(stroke
				(width 0.1524)
				(type default)
			)
			(layer "B.SilkS")
		)
		(fp_line
			(start 0.7874 0.4064)
			(end 0.7874 -0.4064)
			(stroke
				(width 0.1524)
				(type default)
			)
			(layer "B.SilkS")
		)
		(fp_line
			(start -0.7874 -0.4064)
			(end -0.7874 0.4064)
			(stroke
				(width 0.1524)
				(type default)
			)
			(layer "B.SilkS")
		)
		(fp_line
			(start 0.7874 -0.4064)
			(end -0.7874 -0.4064)
			(stroke
				(width 0.1524)
				(type default)
			)
			(layer "B.SilkS")
		)
		(fp_line
			(start -0.67945 0.3048)
			(end -0.120396 0.3048)
			(stroke
				(width 0.1)
				(type default)
			)
			(layer "B.Fab")
		)
		(fp_line
			(start -0.120396 0.3048)
			(end -0.120396 0.2794)
			(stroke
				(width 0.1)
				(type default)
			)
			(layer "B.Fab")
		)
		(fp_line
			(start 0.12065 0.3048)
			(end 0.67945 0.3048)
			(stroke
				(width 0.1)
				(type default)
			)
			(layer "B.Fab")
		)
		(fp_line
			(start 0.67945 0.3048)
			(end 0.67945 -0.305054)
			(stroke
				(width 0.1)
				(type default)
			)
			(layer "B.Fab")
		)
		(fp_line
			(start -0.120396 0.2794)
			(end 0.12065 0.2794)
			(stroke
				(width 0.1)
				(type default)
			)
			(layer "B.Fab")
		)
		(fp_line
			(start 0.12065 0.2794)
			(end 0.12065 0.3048)
			(stroke
				(width 0.1)
				(type default)
			)
			(layer "B.Fab")
		)
		(fp_line
			(start -0.12065 -0.2794)
			(end -0.12065 -0.3048)
			(stroke
				(width 0.1)
				(type default)
			)
			(layer "B.Fab")
		)
		(fp_line
			(start 0.12065 -0.2794)
			(end -0.12065 -0.2794)
			(stroke
				(width 0.1)
				(type default)
			)
			(layer "B.Fab")
		)
		(fp_line
			(start -0.67945 -0.3048)
			(end -0.67945 0.3048)
			(stroke
				(width 0.1)
				(type default)
			)
			(layer "B.Fab")
		)
		(fp_line
			(start -0.12065 -0.3048)
			(end -0.67945 -0.3048)
			(stroke
				(width 0.1)
				(type default)
			)
			(layer "B.Fab")
		)
		(fp_line
			(start 0.12065 -0.305054)
			(end 0.12065 -0.2794)
			(stroke
				(width 0.1)
				(type default)
			)
			(layer "B.Fab")
		)
		(fp_line
			(start 0.67945 -0.305054)
			(end 0.12065 -0.305054)
			(stroke
				(width 0.1)
				(type default)
			)
			(layer "B.Fab")
		)
		(pad "1" smd circle
			(at 0.40005 0 90)
			(size 0 0)
			(layers "B.Cu" "B.Mask" "B.Paste")
			(net "NC_P0V9_RETIMER_CPU1_IMON4")
		)
		(pad "2" smd circle
			(at -0.40005 0 90)
			(size 0 0)
			(layers "B.Cu" "B.Mask" "B.Paste")
			(net "GND")
		)
	)
	(footprint ""
		(layer "B.Cu")
		(at 108.371386 -264.354564)
		(property "Reference" "C3902"
			(at 0 0 0)
			(layer "B.SilkS")
			(hide yes)
			(effects
				(font
					(size 1.27 1.27)
				)
				(justify mirror)
			)
		)
		(property "Value" ""
			(at 0 0 0)
			(layer "B.Fab")
			(effects
				(font
					(size 1.27 1.27)
				)
				(justify mirror)
			)
		)
		(duplicate_pad_numbers_are_jumpers no)
		(fp_line
			(start -0.7874 -0.4064)
			(end -0.7874 0.4064)
			(stroke
				(width 0.1524)
				(type default)
			)
			(layer "B.SilkS")
		)
		(fp_line
			(start -0.7874 0.4064)
			(end 0.7874 0.4064)
			(stroke
				(width 0.1524)
				(type default)
			)
			(layer "B.SilkS")
		)
		(fp_line
			(start 0.7874 -0.4064)
			(end -0.7874 -0.4064)
			(stroke
				(width 0.1524)
				(type default)
			)
			(layer "B.SilkS")
		)
		(fp_line
			(start 0.7874 0.4064)
			(end 0.7874 -0.4064)
			(stroke
				(width 0.1524)
				(type default)
			)
			(layer "B.SilkS")
		)
		(fp_line
			(start -0.67945 -0.3048)
			(end -0.67945 0.3048)
			(stroke
				(width 0.1)
				(type default)
			)
			(layer "B.Fab")
		)
		(fp_line
			(start -0.67945 0.3048)
			(end -0.120396 0.3048)
			(stroke
				(width 0.1)
				(type default)
			)
			(layer "B.Fab")
		)
		(fp_line
			(start -0.12065 -0.3048)
			(end -0.67945 -0.3048)
			(stroke
				(width 0.1)
				(type default)
			)
			(layer "B.Fab")
		)
		(fp_line
			(start -0.12065 -0.2794)
			(end -0.12065 -0.3048)
			(stroke
				(width 0.1)
				(type default)
			)
			(layer "B.Fab")
		)
		(fp_line
			(start -0.120396 0.2794)
			(end 0.12065 0.2794)
			(stroke
				(width 0.1)
				(type default)
			)
			(layer "B.Fab")
		)
		(fp_line
			(start -0.120396 0.3048)
			(end -0.120396 0.2794)
			(stroke
				(width 0.1)
				(type default)
			)
			(layer "B.Fab")
		)
		(fp_line
			(start 0.12065 -0.305054)
			(end 0.12065 -0.2794)
			(stroke
				(width 0.1)
				(type default)
			)
			(layer "B.Fab")
		)
		(fp_line
			(start 0.12065 -0.2794)
			(end -0.12065 -0.2794)
			(stroke
				(width 0.1)
				(type default)
			)
			(layer "B.Fab")
		)
		(fp_line
			(start 0.12065 0.2794)
			(end 0.12065 0.3048)
			(stroke
				(width 0.1)
				(type default)
			)
			(layer "B.Fab")
		)
		(fp_line
			(start 0.12065 0.3048)
			(end 0.67945 0.3048)
			(stroke
				(width 0.1)
				(type default)
			)
			(layer "B.Fab")
		)
		(fp_line
			(start 0.67945 -0.305054)
			(end 0.12065 -0.305054)
			(stroke
				(width 0.1)
				(type default)
			)
			(layer "B.Fab")
		)
		(fp_line
			(start 0.67945 0.3048)
			(end 0.67945 -0.305054)
			(stroke
				(width 0.1)
				(type default)
			)
			(layer "B.Fab")
		)
		(pad "1" smd circle
			(at 0.40005 0 180)
			(size 0 0)
			(layers "B.Cu" "B.Mask" "B.Paste")
			(net "PVDD11_S3_P1")
		)
		(pad "2" smd circle
			(at -0.40005 0 180)
			(size 0 0)
			(layers "B.Cu" "B.Mask" "B.Paste")
			(net "GND")
		)
	)
)
